# BASEBOARD_FAB2 (Tioga Pass) — schematic netlist excerpt (pin names and nets, part order shuffled) for the footprints in the layout excerpt that follows; sources: Cadence DE-HDL packaged netlist, KiCad conversion of Wiwynn_Tioga_Pass_MB.brd

Q9W4  LMV331IDCKRG4-GP  pkg DISCRET-G  page 249
  \+in\  = FM_TPM_PRES_RST_N
  GND  = GND
  \-in\  = VREF_2V2
  \out\  = FM_TPM_PRES_N
  VCC  = P5V_STBY

Q6W2  NPN  MMBT3904 IC  pkg SM  page 168
  B  = FM_UART_SEL_N
  E  = GND
  C  = FM_SOL_UART_CH_SEL

C2U5  CAP  0.22UF 16V 10% X7R  pkg 0402  page 107 : A = P3E_CPU0_PE1_PCH_RXP<1> ; B = P3E_CPU0_PE1_SS_RXP<1>

(kicad_pcb
	(version 20260206)
	(generator "pcbnew")
	(generator_version "10.0")
	(general
		(thickness 1.6)
		(legacy_teardrops no)
	)
	(paper "A4")
	(title_block
		(title "Wiwynn_Tioga_Pass_MB.brd")
		(comment 1 "Tioga Pass / footprints 2428-2430 of 4770")
	)
	(layers
		(0 "F.Cu" signal "TOP")
		(4 "In1.Cu" signal "L2GND")
		(6 "In2.Cu" signal "L3")
		(8 "In3.Cu" signal "L4GND")
		(10 "In4.Cu" signal "L5")
		(12 "In5.Cu" signal "L6GND")
		(14 "In6.Cu" signal "L7VCC")
		(16 "In7.Cu" signal "L8VCC")
		(18 "In8.Cu" signal "L9GND")
		(20 "In9.Cu" signal "L10")
		(22 "In10.Cu" signal "L11GND")
		(24 "In11.Cu" signal "L12")
		(26 "In12.Cu" signal "L13GND")
		(2 "B.Cu" signal "BOTTOM")
		(9 "F.Adhes" user "F.Adhesive")
		(11 "B.Adhes" user "B.Adhesive")
		(13 "F.Paste" user "Package Geometry/Pastemask Top")
		(15 "B.Paste" user "Package Geometry/Pastemask Bottom")
		(5 "F.SilkS" user "Ref Des/Silkscreen Top")
		(7 "B.SilkS" user "Ref Des/Silkscreen Bottom")
		(1 "F.Mask" user "Board Geometry/Soldermask Top")
		(3 "B.Mask" user "Board Geometry/Soldermask Bottom")
		(17 "Dwgs.User" user "User.Drawings")
		(19 "Cmts.User" user "User.Comments")
		(21 "Eco1.User" user "User.Eco1")
		(23 "Eco2.User" user "User.Eco2")
		(25 "Edge.Cuts" user "Board Geometry/Outline")
		(27 "Margin" user)
		(31 "F.CrtYd" user "Package Geometry/Place Bound Top")
		(29 "B.CrtYd" user "Package Geometry/Place Bound Bottom")
		(35 "F.Fab" user "Ref Des/Assembly Top")
		(33 "B.Fab" user "Ref Des/Assembly Bottom")
	)
	(footprint ""
		(layer "B.Cu")
		(at 336.140806 -61.257434)
		(property "Reference" "C2U5"
			(at 0 0 0)
			(layer "B.SilkS")
			(hide yes)
			(effects
				(font
					(size 1.27 1.27)
				)
				(justify mirror)
			)
		)
		(property "Value" ""
			(at 0 0 0)
			(layer "B.Fab")
			(effects
				(font
					(size 1.27 1.27)
				)
				(justify mirror)
			)
		)
		(duplicate_pad_numbers_are_jumpers no)
		(fp_poly
			(pts
				(xy -0.3048 -0.1016) (xy -0.3048 0.9906) (xy 0.3048 0.9906) (xy 0.3048 -0.1016)
			)
			(stroke
				(width 0)
				(type default)
			)
			(fill no)
			(layer "B.CrtYd")
		)
		(fp_line
			(start -0.3048 -0.1016)
			(end 0.3048 -0.1016)
			(stroke
				(width 0.1)
				(type default)
			)
			(layer "B.Fab")
		)
		(fp_line
			(start -0.3048 0.9906)
			(end -0.3048 -0.1016)
			(stroke
				(width 0.1)
				(type default)
			)
			(layer "B.Fab")
		)
		(fp_line
			(start 0.3048 -0.1016)
			(end 0.3048 0.9906)
			(stroke
				(width 0.1)
				(type default)
			)
			(layer "B.Fab")
		)
		(fp_line
			(start 0.3048 0.9906)
			(end -0.3048 0.9906)
			(stroke
				(width 0.1)
				(type default)
			)
			(layer "B.Fab")
		)
		(pad "1" smd rect
			(at 0 0 180)
			(size 0.508 0.508)
			(layers "B.Cu" "B.Mask" "B.Paste")
			(net "P3E_CPU0_PE1_PCH_RXP<1>")
		)
		(pad "2" smd rect
			(at 0 0.889 180)
			(size 0.508 0.508)
			(layers "B.Cu" "B.Mask" "B.Paste")
			(net "P3E_CPU0_PE1_SS_RXP<1>")
		)
		(zone
			(layer "B.Cu")
			(hatch none 0.5)
			(connect_pads
				(clearance 0)
			)
			(min_thickness 0.25)
			(keepout
				(tracks allowed)
				(vias not_allowed)
				(pads allowed)
				(copperpour not_allowed)
				(footprints allowed)
			)
			(placement
				(enabled no)
				(sheetname "")
			)
			(fill
				(thermal_gap 0.5)
				(thermal_bridge_width 0.5)
				(island_removal_mode 0)
			)
			(polygon
				(pts
					(xy 336.394806 -61.003434) (xy 335.886806 -61.003434) (xy 335.886806 -60.622434) (xy 336.394806 -60.622434)
				)
			)
		)
		(zone
			(layer "B.Cu")
			(hatch none 0.5)
			(connect_pads
				(clearance 0)
			)
			(min_thickness 0.25)
			(keepout
				(tracks not_allowed)
				(vias allowed)
				(pads allowed)
				(copperpour not_allowed)
				(footprints allowed)
			)
			(placement
				(enabled no)
				(sheetname "")
			)
			(fill
				(thermal_gap 0.5)
				(thermal_bridge_width 0.5)
				(island_removal_mode 0)
			)
			(polygon
				(pts
					(xy 336.394806 -60.622434) (xy 335.886806 -60.622434) (xy 335.886806 -61.003434) (xy 336.394806 -61.003434)
				)
			)
		)
	)
	(footprint ""
		(layer "B.Cu")
		(at 481.0379 -147.977098)
		(property "Reference" "Q6W2"
			(at 0.229362 -1.2065 0)
			(unlocked yes)
			(layer "B.SilkS")
			(effects
				(font
					(size 0.4064 0.254)
					(thickness 0.1524)
				)
				(justify left mirror)
			)
		)
		(property "Value" ""
			(at 0 0 0)
			(layer "B.Fab")
			(effects
				(font
					(size 1.27 1.27)
				)
				(justify mirror)
			)
		)
		(duplicate_pad_numbers_are_jumpers no)
		(fp_line
			(start -1.778 -0.5715)
			(end -1.778 0.3175)
			(stroke
				(width 0.1524)
				(type default)
			)
			(layer "B.SilkS")
		)
		(fp_line
			(start -1.778 2.4765)
			(end -1.778 1.5875)
			(stroke
				(width 0.1524)
				(type default)
			)
			(layer "B.SilkS")
		)
		(fp_line
			(start -0.9525 -0.5715)
			(end -1.778 -0.5715)
			(stroke
				(width 0.1524)
				(type default)
			)
			(layer "B.SilkS")
		)
		(fp_line
			(start -0.9525 2.4765)
			(end -1.778 2.4765)
			(stroke
				(width 0.1524)
				(type default)
			)
			(layer "B.SilkS")
		)
		(fp_line
			(start -0.381 0.635)
			(end -0.381 1.27)
			(stroke
				(width 0.1524)
				(type default)
			)
			(layer "B.SilkS")
		)
		(fp_circle
			(center 0.758952 -0.88773)
			(end 0.885952 -0.88773)
			(stroke
				(width 0.254)
				(type default)
			)
			(fill no)
			(layer "B.SilkS")
		)
		(fp_poly
			(pts
				(xy -1.778 2.4765) (xy -0.381 2.4765) (xy -0.381 -0.5715) (xy -1.778 -0.5715)
			)
			(stroke
				(width 0)
				(type default)
			)
			(fill no)
			(layer "B.CrtYd")
		)
		(fp_line
			(start -1.778 -0.5715)
			(end -0.381 -0.5715)
			(stroke
				(width 0.1)
				(type default)
			)
			(layer "B.Fab")
		)
		(fp_line
			(start -1.778 2.4765)
			(end -1.778 -0.5715)
			(stroke
				(width 0.1)
				(type default)
			)
			(layer "B.Fab")
		)
		(fp_line
			(start -0.381 -0.5715)
			(end -0.381 2.4765)
			(stroke
				(width 0.1)
				(type default)
			)
			(layer "B.Fab")
		)
		(fp_line
			(start -0.381 2.4765)
			(end -1.778 2.4765)
			(stroke
				(width 0.1)
				(type default)
			)
			(layer "B.Fab")
		)
		(fp_circle
			(center 0.9525 -0.9271)
			(end 1.0795 -0.9271)
			(stroke
				(width 0.254)
				(type default)
			)
			(fill no)
			(layer "B.Fab")
		)
		(pad "1" smd rect
			(at 0 0 180)
			(size 1.143 0.508)
			(layers "B.Cu" "B.Mask" "B.Paste")
			(net "FM_UART_SEL_N")
		)
		(pad "2" smd rect
			(at 0 1.905 180)
			(size 1.143 0.508)
			(layers "B.Cu" "B.Mask" "B.Paste")
			(net "GND")
		)
		(pad "3" smd rect
			(at -2.159 0.9525 180)
			(size 1.143 0.508)
			(layers "B.Cu" "B.Mask" "B.Paste")
			(net "FM_SOL_UART_CH_SEL")
		)
	)
	(footprint ""
		(layer "B.Cu")
		(at 447.04 -19.939 -90)
		(property "Reference" "Q9W4"
			(at 0 0 90)
			(layer "B.SilkS")
			(hide yes)
			(effects
				(font
					(size 1.27 1.27)
				)
				(justify mirror)
			)
		)
		(property "Value" "*"
			(at 2.3368 -8.8011 270)
			(unlocked yes)
			(layer "B.Fab")
			(hide yes)
			(effects
				(font
					(size 1.27 1.016)
					(thickness 0.1524)
				)
				(justify mirror)
			)
		)
		(property "Device Type" "LMV331IDCKRG4-GP_DISCRET-G-LMVA"
			(at 2.3114 -10.5283 270)
			(unlocked yes)
			(layer "B.Fab")
			(hide yes)
			(effects
				(font
					(size 1.27 1.016)
					(thickness 0.1524)
				)
				(justify mirror)
			)
		)
		(duplicate_pad_numbers_are_jumpers no)
		(fp_line
			(start -1.27 1.7018)
			(end 1.27 1.7018)
			(stroke
				(width 0.1524)
				(type default)
			)
			(layer "B.SilkS")
		)
		(fp_line
			(start 1.27 1.7018)
			(end 1.27 -1.7018)
			(stroke
				(width 0.1524)
				(type default)
			)
			(layer "B.SilkS")
		)
		(fp_line
			(start -1.27 -1.7018)
			(end -1.27 1.7018)
			(stroke
				(width 0.1524)
				(type default)
			)
			(layer "B.SilkS")
		)
		(fp_line
			(start 1.27 -1.7018)
			(end -1.27 -1.7018)
			(stroke
				(width 0.1524)
				(type default)
			)
			(layer "B.SilkS")
		)
		(fp_line
			(start -1.3843 -1.8034)
			(end -1.3843 -1.1176)
			(stroke
				(width 0.3302)
				(type default)
			)
			(layer "B.SilkS")
		)
		(fp_line
			(start -0.6604 -1.8034)
			(end -1.3843 -1.8034)
			(stroke
				(width 0.3302)
				(type default)
			)
			(layer "B.SilkS")
		)
		(fp_rect
			(start 1.524 1.9558)
			(end -1.524 -1.9558)
			(stroke
				(width 0)
				(type default)
			)
			(fill no)
			(layer "B.CrtYd")
		)
		(fp_poly
			(pts
				(xy 1.524 -1.9558) (xy -1.524 -1.9558) (xy -1.524 1.9558) (xy 1.524 1.9558)
			)
			(stroke
				(width 0)
				(type default)
			)
			(fill no)
			(layer "B.Fab")
		)
		(pad "1" smd rect
			(at -0.65024 -0.8255 90)
			(size 0.4064 1.2192)
			(layers "B.Cu" "B.Mask" "B.Paste")
			(net "FM_TPM_PRES_RST_N")
		)
		(pad "2" smd rect
			(at 0 -0.8255 90)
			(size 0.4064 1.2192)
			(layers "B.Cu" "B.Mask" "B.Paste")
			(net "GND")
		)
		(pad "3" smd rect
			(at 0.65024 -0.8255 90)
			(size 0.4064 1.2192)
			(layers "B.Cu" "B.Mask" "B.Paste")
			(net "VREF_2V2")
		)
		(pad "4" smd rect
			(at 0.65024 0.8255 90)
			(size 0.4064 1.2192)
			(layers "B.Cu" "B.Mask" "B.Paste")
			(net "FM_TPM_PRES_N")
		)
		(pad "5" smd rect
			(at -0.65024 0.8255 90)
			(size 0.4064 1.2192)
			(layers "B.Cu" "B.Mask" "B.Paste")
			(net "P5V_STBY")
		)
	)
)
